(kicad_pcb
	(version 20260206)
	(generator "pcbnew")
	(generator_version "10.0")
	(general
		(thickness 1.6)
		(legacy_teardrops no)
	)
	(paper "A4")
	(title_block
		(title "04192023_DAF0TMB3IC0_F0TG_MB_C_brd_V02_OCP.brd")
		(comment 1 "Grand Teton / footprint 2100 of 8354 (J24), pads 114-226 of 291")
	)
	(layers
		(0 "F.Cu" signal "TOP")
		(4 "In1.Cu" signal "GND")
		(6 "In2.Cu" signal "IN1")
		(8 "In3.Cu" signal "GND1")
		(10 "In4.Cu" signal "IN2")
		(12 "In5.Cu" signal "GND2")
		(14 "In6.Cu" signal "IN3")
		(16 "In7.Cu" signal "GND3")
		(18 "In8.Cu" signal "VCC")
		(20 "In9.Cu" signal "VCC1")
		(22 "In10.Cu" signal "GND4")
		(24 "In11.Cu" signal "IN4")
		(26 "In12.Cu" signal "GND5")
		(28 "In13.Cu" signal "IN5")
		(30 "In14.Cu" signal "GND6")
		(32 "In15.Cu" signal "IN6")
		(34 "In16.Cu" signal "GND7")
		(2 "B.Cu" signal "BOTTOM")
		(9 "F.Adhes" user "F.Adhesive")
		(11 "B.Adhes" user "B.Adhesive")
		(13 "F.Paste" user "Package Geometry/Pastemask Top")
		(15 "B.Paste" user "Package Geometry/Pastemask Bottom")
		(5 "F.SilkS" user "Ref Des/Silkscreen Top")
		(7 "B.SilkS" user "Ref Des/Silkscreen Bottom")
		(1 "F.Mask" user "Board Geometry/Soldermask Top")
		(3 "B.Mask" user "Board Geometry/Soldermask Bottom")
		(17 "Dwgs.User" user "User.Drawings")
		(19 "Cmts.User" user "User.Comments")
		(21 "Eco1.User" user "User.Eco1")
		(23 "Eco2.User" user "User.Eco2")
		(25 "Edge.Cuts" user "Board Geometry/Outline")
		(27 "Margin" user)
		(31 "F.CrtYd" user "Package Geometry/Place Bound Top")
		(29 "B.CrtYd" user "Package Geometry/Place Bound Bottom")
		(35 "F.Fab" user "Ref Des/Assembly Top")
		(33 "B.Fab" user "Ref Des/Assembly Bottom")
	)
	(footprint ""
		(layer "F.Cu")
		(at 57.378092 -255.560322 180)
		(property "Reference" "J24"
			(at 1.914906 -84.58708 0)
			(unlocked yes)
			(layer "F.SilkS")
			(effects
				(font
					(size 0.7874 0.5842)
					(thickness 0.1524)
				)
			)
		)
		(property "Value" ""
			(at 0 0 180)
			(layer "F.Fab")
			(effects
				(font
					(size 1.27 1.27)
				)
			)
		)
		(duplicate_pad_numbers_are_jumpers no)
		(pad "114" smd rect
			(at -2.050034 37.824918 90)
			(size 0.519938 1.4986)
			(layers "F.Cu" "F.Mask" "F.Paste")
			(net "GND")
		)
		(pad "115" smd rect
			(at -2.050034 38.675056 90)
			(size 0.519938 1.4986)
			(layers "F.Cu" "F.Mask" "F.Paste")
			(net "M_A_CPU1_SB_DQS_DP<1>")
		)
		(pad "116" smd rect
			(at -2.050034 39.52494 90)
			(size 0.519938 1.4986)
			(layers "F.Cu" "F.Mask" "F.Paste")
			(net "M_A_CPU1_SB_DQS_DN<1>")
		)
		(pad "117" smd rect
			(at -2.050034 40.375078 90)
			(size 0.519938 1.4986)
			(layers "F.Cu" "F.Mask" "F.Paste")
			(net "GND")
		)
		(pad "118" smd rect
			(at -2.050034 41.224962 90)
			(size 0.519938 1.4986)
			(layers "F.Cu" "F.Mask" "F.Paste")
			(net "M_A_CPU1_SB_DQ<12>")
		)
		(pad "119" smd rect
			(at -2.050034 42.0751 90)
			(size 0.519938 1.4986)
			(layers "F.Cu" "F.Mask" "F.Paste")
			(net "GND")
		)
		(pad "120" smd rect
			(at -2.050034 42.924984 90)
			(size 0.519938 1.4986)
			(layers "F.Cu" "F.Mask" "F.Paste")
			(net "M_A_CPU1_SB_DQ<13>")
		)
		(pad "121" smd rect
			(at -2.050034 43.775122 90)
			(size 0.519938 1.4986)
			(layers "F.Cu" "F.Mask" "F.Paste")
			(net "GND")
		)
		(pad "122" smd rect
			(at -2.050034 44.625006 90)
			(size 0.519938 1.4986)
			(layers "F.Cu" "F.Mask" "F.Paste")
			(net "M_A_CPU1_SB_DQ<16>")
		)
		(pad "123" smd rect
			(at -2.050034 45.47489 90)
			(size 0.519938 1.4986)
			(layers "F.Cu" "F.Mask" "F.Paste")
			(net "GND")
		)
		(pad "124" smd rect
			(at -2.050034 46.325028 90)
			(size 0.519938 1.4986)
			(layers "F.Cu" "F.Mask" "F.Paste")
			(net "M_A_CPU1_SB_DQ<17>")
		)
		(pad "125" smd rect
			(at -2.050034 47.174912 90)
			(size 0.519938 1.4986)
			(layers "F.Cu" "F.Mask" "F.Paste")
			(net "GND")
		)
		(pad "126" smd rect
			(at -2.050034 48.02505 90)
			(size 0.519938 1.4986)
			(layers "F.Cu" "F.Mask" "F.Paste")
			(net "M_A_CPU1_SB_DQS_DP<2>")
		)
		(pad "127" smd rect
			(at -2.050034 48.874934 90)
			(size 0.519938 1.4986)
			(layers "F.Cu" "F.Mask" "F.Paste")
			(net "M_A_CPU1_SB_DQS_DN<2>")
		)
		(pad "128" smd rect
			(at -2.050034 49.725072 90)
			(size 0.519938 1.4986)
			(layers "F.Cu" "F.Mask" "F.Paste")
			(net "GND")
		)
		(pad "129" smd rect
			(at -2.050034 50.574956 90)
			(size 0.519938 1.4986)
			(layers "F.Cu" "F.Mask" "F.Paste")
			(net "M_A_CPU1_SB_DQ<20>")
		)
		(pad "130" smd rect
			(at -2.050034 51.425094 90)
			(size 0.519938 1.4986)
			(layers "F.Cu" "F.Mask" "F.Paste")
			(net "GND")
		)
		(pad "131" smd rect
			(at -2.050034 52.274978 90)
			(size 0.519938 1.4986)
			(layers "F.Cu" "F.Mask" "F.Paste")
			(net "M_A_CPU1_SB_DQ<21>")
		)
		(pad "132" smd rect
			(at -2.050034 53.125116 90)
			(size 0.519938 1.4986)
			(layers "F.Cu" "F.Mask" "F.Paste")
			(net "GND")
		)
		(pad "133" smd rect
			(at -2.050034 53.975 90)
			(size 0.519938 1.4986)
			(layers "F.Cu" "F.Mask" "F.Paste")
			(net "M_A_CPU1_SB_DQ<24>")
		)
		(pad "134" smd rect
			(at -2.050034 54.824884 90)
			(size 0.519938 1.4986)
			(layers "F.Cu" "F.Mask" "F.Paste")
			(net "GND")
		)
		(pad "135" smd rect
			(at -2.050034 55.675022 90)
			(size 0.519938 1.4986)
			(layers "F.Cu" "F.Mask" "F.Paste")
			(net "M_A_CPU1_SB_DQ<25>")
		)
		(pad "136" smd rect
			(at -2.050034 56.524906 90)
			(size 0.519938 1.4986)
			(layers "F.Cu" "F.Mask" "F.Paste")
			(net "GND")
		)
		(pad "137" smd rect
			(at -2.050034 57.375044 90)
			(size 0.519938 1.4986)
			(layers "F.Cu" "F.Mask" "F.Paste")
			(net "M_A_CPU1_SB_DQS_DP<3>")
		)
		(pad "138" smd rect
			(at -2.050034 58.224928 90)
			(size 0.519938 1.4986)
			(layers "F.Cu" "F.Mask" "F.Paste")
			(net "M_A_CPU1_SB_DQS_DN<3>")
		)
		(pad "139" smd rect
			(at -2.050034 59.075066 90)
			(size 0.519938 1.4986)
			(layers "F.Cu" "F.Mask" "F.Paste")
			(net "GND")
		)
		(pad "140" smd rect
			(at -2.050034 59.92495 90)
			(size 0.519938 1.4986)
			(layers "F.Cu" "F.Mask" "F.Paste")
			(net "M_A_CPU1_SB_DQ<28>")
		)
		(pad "141" smd rect
			(at -2.050034 60.775088 90)
			(size 0.519938 1.4986)
			(layers "F.Cu" "F.Mask" "F.Paste")
			(net "GND")
		)
		(pad "142" smd rect
			(at -2.050034 61.624972 90)
			(size 0.519938 1.4986)
			(layers "F.Cu" "F.Mask" "F.Paste")
			(net "M_A_CPU1_SB_DQ<29>")
		)
		(pad "143" smd rect
			(at -2.050034 62.47511 90)
			(size 0.519938 1.4986)
			(layers "F.Cu" "F.Mask" "F.Paste")
			(net "GND")
		)
		(pad "144" smd rect
			(at -2.050034 63.324994 90)
			(size 0.519938 1.4986)
			(layers "F.Cu" "F.Mask" "F.Paste")
			(net "Net_2257")
		)
		(pad "145" smd rect
			(at 2.050034 -63.324994 90)
			(size 0.519938 1.4986)
			(layers "F.Cu" "F.Mask" "F.Paste")
			(net "P12V_MEM_CPU1")
		)
		(pad "146" smd rect
			(at 2.050034 -62.47511 90)
			(size 0.519938 1.4986)
			(layers "F.Cu" "F.Mask" "F.Paste")
			(net "P12V_MEM_CPU1")
		)
		(pad "147" smd rect
			(at 2.050034 -61.624972 90)
			(size 0.519938 1.4986)
			(layers "F.Cu" "F.Mask" "F.Paste")
			(net "PWRGD_CHA_CPU1_DIMM0")
		)
		(pad "148" smd rect
			(at 2.050034 -60.775088 90)
			(size 0.519938 1.4986)
			(layers "F.Cu" "F.Mask" "F.Paste")
			(net "PD_CHA_CPU1_DIMM0_SAA")
		)
		(pad "149" smd rect
			(at 2.050034 -59.92495 90)
			(size 0.519938 1.4986)
			(layers "F.Cu" "F.Mask" "F.Paste")
			(net "Net_2258")
		)
		(pad "150" smd rect
			(at 2.050034 -59.075066 90)
			(size 0.519938 1.4986)
			(layers "F.Cu" "F.Mask" "F.Paste")
			(net "Net_2259")
		)
		(pad "151" smd rect
			(at 2.050034 -58.224928 90)
			(size 0.519938 1.4986)
			(layers "F.Cu" "F.Mask" "F.Paste")
			(net "GND")
		)
		(pad "152" smd rect
			(at 2.050034 -57.375044 90)
			(size 0.519938 1.4986)
			(layers "F.Cu" "F.Mask" "F.Paste")
			(net "M_A_CPU1_SA_DQ<2>")
		)
		(pad "153" smd rect
			(at 2.050034 -56.524906 90)
			(size 0.519938 1.4986)
			(layers "F.Cu" "F.Mask" "F.Paste")
			(net "GND")
		)
		(pad "154" smd rect
			(at 2.050034 -55.675022 90)
			(size 0.519938 1.4986)
			(layers "F.Cu" "F.Mask" "F.Paste")
			(net "M_A_CPU1_SA_DQ<3>")
		)
		(pad "155" smd rect
			(at 2.050034 -54.824884 90)
			(size 0.519938 1.4986)
			(layers "F.Cu" "F.Mask" "F.Paste")
			(net "GND")
		)
		(pad "156" smd rect
			(at 2.050034 -53.975 90)
			(size 0.519938 1.4986)
			(layers "F.Cu" "F.Mask" "F.Paste")
			(net "M_A_CPU1_SA_DQS_DN<5>")
		)
		(pad "157" smd rect
			(at 2.050034 -53.125116 90)
			(size 0.519938 1.4986)
			(layers "F.Cu" "F.Mask" "F.Paste")
			(net "M_A_CPU1_SA_DQS_DP<5>")
		)
		(pad "158" smd rect
			(at 2.050034 -52.274978 90)
			(size 0.519938 1.4986)
			(layers "F.Cu" "F.Mask" "F.Paste")
			(net "GND")
		)
		(pad "159" smd rect
			(at 2.050034 -51.425094 90)
			(size 0.519938 1.4986)
			(layers "F.Cu" "F.Mask" "F.Paste")
			(net "M_A_CPU1_SA_DQ<6>")
		)
		(pad "160" smd rect
			(at 2.050034 -50.574956 90)
			(size 0.519938 1.4986)
			(layers "F.Cu" "F.Mask" "F.Paste")
			(net "GND")
		)
		(pad "161" smd rect
			(at 2.050034 -49.725072 90)
			(size 0.519938 1.4986)
			(layers "F.Cu" "F.Mask" "F.Paste")
			(net "M_A_CPU1_SA_DQ<7>")
		)
		(pad "162" smd rect
			(at 2.050034 -48.874934 90)
			(size 0.519938 1.4986)
			(layers "F.Cu" "F.Mask" "F.Paste")
			(net "GND")
		)
		(pad "163" smd rect
			(at 2.050034 -48.02505 90)
			(size 0.519938 1.4986)
			(layers "F.Cu" "F.Mask" "F.Paste")
			(net "M_A_CPU1_SA_DQ<10>")
		)
		(pad "164" smd rect
			(at 2.050034 -47.174912 90)
			(size 0.519938 1.4986)
			(layers "F.Cu" "F.Mask" "F.Paste")
			(net "GND")
		)
		(pad "165" smd rect
			(at 2.050034 -46.325028 90)
			(size 0.519938 1.4986)
			(layers "F.Cu" "F.Mask" "F.Paste")
			(net "M_A_CPU1_SA_DQ<11>")
		)
		(pad "166" smd rect
			(at 2.050034 -45.47489 90)
			(size 0.519938 1.4986)
			(layers "F.Cu" "F.Mask" "F.Paste")
			(net "GND")
		)
		(pad "167" smd rect
			(at 2.050034 -44.625006 90)
			(size 0.519938 1.4986)
			(layers "F.Cu" "F.Mask" "F.Paste")
			(net "M_A_CPU1_SA_DQS_DN<6>")
		)
		(pad "168" smd rect
			(at 2.050034 -43.775122 90)
			(size 0.519938 1.4986)
			(layers "F.Cu" "F.Mask" "F.Paste")
			(net "M_A_CPU1_SA_DQS_DP<6>")
		)
		(pad "169" smd rect
			(at 2.050034 -42.924984 90)
			(size 0.519938 1.4986)
			(layers "F.Cu" "F.Mask" "F.Paste")
			(net "GND")
		)
		(pad "170" smd rect
			(at 2.050034 -42.0751 90)
			(size 0.519938 1.4986)
			(layers "F.Cu" "F.Mask" "F.Paste")
			(net "M_A_CPU1_SA_DQ<14>")
		)
		(pad "171" smd rect
			(at 2.050034 -41.224962 90)
			(size 0.519938 1.4986)
			(layers "F.Cu" "F.Mask" "F.Paste")
			(net "GND")
		)
		(pad "172" smd rect
			(at 2.050034 -40.375078 90)
			(size 0.519938 1.4986)
			(layers "F.Cu" "F.Mask" "F.Paste")
			(net "M_A_CPU1_SA_DQ<15>")
		)
		(pad "173" smd rect
			(at 2.050034 -39.52494 90)
			(size 0.519938 1.4986)
			(layers "F.Cu" "F.Mask" "F.Paste")
			(net "GND")
		)
		(pad "174" smd rect
			(at 2.050034 -38.675056 90)
			(size 0.519938 1.4986)
			(layers "F.Cu" "F.Mask" "F.Paste")
			(net "M_A_CPU1_SA_DQ<18>")
		)
		(pad "175" smd rect
			(at 2.050034 -37.824918 90)
			(size 0.519938 1.4986)
			(layers "F.Cu" "F.Mask" "F.Paste")
			(net "GND")
		)
		(pad "176" smd rect
			(at 2.050034 -36.975034 90)
			(size 0.519938 1.4986)
			(layers "F.Cu" "F.Mask" "F.Paste")
			(net "M_A_CPU1_SA_DQ<19>")
		)
		(pad "177" smd rect
			(at 2.050034 -36.124896 90)
			(size 0.519938 1.4986)
			(layers "F.Cu" "F.Mask" "F.Paste")
			(net "GND")
		)
		(pad "178" smd rect
			(at 2.050034 -35.275012 90)
			(size 0.519938 1.4986)
			(layers "F.Cu" "F.Mask" "F.Paste")
			(net "M_A_CPU1_SA_DQS_DN<7>")
		)
		(pad "179" smd rect
			(at 2.050034 -34.425128 90)
			(size 0.519938 1.4986)
			(layers "F.Cu" "F.Mask" "F.Paste")
			(net "M_A_CPU1_SA_DQS_DP<7>")
		)
		(pad "180" smd rect
			(at 2.050034 -33.57499 90)
			(size 0.519938 1.4986)
			(layers "F.Cu" "F.Mask" "F.Paste")
			(net "GND")
		)
		(pad "181" smd rect
			(at 2.050034 -32.725106 90)
			(size 0.519938 1.4986)
			(layers "F.Cu" "F.Mask" "F.Paste")
			(net "M_A_CPU1_SA_DQ<22>")
		)
		(pad "182" smd rect
			(at 2.050034 -31.874968 90)
			(size 0.519938 1.4986)
			(layers "F.Cu" "F.Mask" "F.Paste")
			(net "GND")
		)
		(pad "183" smd rect
			(at 2.050034 -31.025084 90)
			(size 0.519938 1.4986)
			(layers "F.Cu" "F.Mask" "F.Paste")
			(net "M_A_CPU1_SA_DQ<23>")
		)
		(pad "184" smd rect
			(at 2.050034 -30.174946 90)
			(size 0.519938 1.4986)
			(layers "F.Cu" "F.Mask" "F.Paste")
			(net "GND")
		)
		(pad "185" smd rect
			(at 2.050034 -29.325062 90)
			(size 0.519938 1.4986)
			(layers "F.Cu" "F.Mask" "F.Paste")
			(net "M_A_CPU1_SA_DQ<26>")
		)
		(pad "186" smd rect
			(at 2.050034 -28.474924 90)
			(size 0.519938 1.4986)
			(layers "F.Cu" "F.Mask" "F.Paste")
			(net "GND")
		)
		(pad "187" smd rect
			(at 2.050034 -27.62504 90)
			(size 0.519938 1.4986)
			(layers "F.Cu" "F.Mask" "F.Paste")
			(net "M_A_CPU1_SA_DQ<27>")
		)
		(pad "188" smd rect
			(at 2.050034 -26.774902 90)
			(size 0.519938 1.4986)
			(layers "F.Cu" "F.Mask" "F.Paste")
			(net "GND")
		)
		(pad "189" smd rect
			(at 2.050034 -25.925018 90)
			(size 0.519938 1.4986)
			(layers "F.Cu" "F.Mask" "F.Paste")
			(net "M_A_CPU1_SA_DQS_DN<8>")
		)
		(pad "190" smd rect
			(at 2.050034 -25.07488 90)
			(size 0.519938 1.4986)
			(layers "F.Cu" "F.Mask" "F.Paste")
			(net "M_A_CPU1_SA_DQS_DP<8>")
		)
		(pad "191" smd rect
			(at 2.050034 -24.224996 90)
			(size 0.519938 1.4986)
			(layers "F.Cu" "F.Mask" "F.Paste")
			(net "GND")
		)
		(pad "192" smd rect
			(at 2.050034 -23.375112 90)
			(size 0.519938 1.4986)
			(layers "F.Cu" "F.Mask" "F.Paste")
			(net "M_A_CPU1_SA_DQ<30>")
		)
		(pad "193" smd rect
			(at 2.050034 -22.524974 90)
			(size 0.519938 1.4986)
			(layers "F.Cu" "F.Mask" "F.Paste")
			(net "GND")
		)
		(pad "194" smd rect
			(at 2.050034 -21.67509 90)
			(size 0.519938 1.4986)
			(layers "F.Cu" "F.Mask" "F.Paste")
			(net "M_A_CPU1_SA_DQ<31>")
		)
		(pad "195" smd rect
			(at 2.050034 -20.824952 90)
			(size 0.519938 1.4986)
			(layers "F.Cu" "F.Mask" "F.Paste")
			(net "GND")
		)
		(pad "196" smd rect
			(at 2.050034 -19.975068 90)
			(size 0.519938 1.4986)
			(layers "F.Cu" "F.Mask" "F.Paste")
			(net "M_A_CPU1_SA_CB<2>")
		)
		(pad "197" smd rect
			(at 2.050034 -19.12493 90)
			(size 0.519938 1.4986)
			(layers "F.Cu" "F.Mask" "F.Paste")
			(net "GND")
		)
		(pad "198" smd rect
			(at 2.050034 -18.275046 90)
			(size 0.519938 1.4986)
			(layers "F.Cu" "F.Mask" "F.Paste")
			(net "M_A_CPU1_SA_CB<3>")
		)
		(pad "199" smd rect
			(at 2.050034 -17.424908 90)
			(size 0.519938 1.4986)
			(layers "F.Cu" "F.Mask" "F.Paste")
			(net "GND")
		)
		(pad "200" smd rect
			(at 2.050034 -16.575024 90)
			(size 0.519938 1.4986)
			(layers "F.Cu" "F.Mask" "F.Paste")
			(net "M_A_CPU1_SA_DQS_DN<9>")
		)
		(pad "201" smd rect
			(at 2.050034 -15.724886 90)
			(size 0.519938 1.4986)
			(layers "F.Cu" "F.Mask" "F.Paste")
			(net "M_A_CPU1_SA_DQS_DP<9>")
		)
		(pad "202" smd rect
			(at 2.050034 -14.875002 90)
			(size 0.519938 1.4986)
			(layers "F.Cu" "F.Mask" "F.Paste")
			(net "GND")
		)
		(pad "203" smd rect
			(at 2.050034 -14.025118 90)
			(size 0.519938 1.4986)
			(layers "F.Cu" "F.Mask" "F.Paste")
			(net "M_A_CPU1_SA_CB<6>")
		)
		(pad "204" smd rect
			(at 2.050034 -13.17498 90)
			(size 0.519938 1.4986)
			(layers "F.Cu" "F.Mask" "F.Paste")
			(net "GND")
		)
		(pad "205" smd rect
			(at 2.050034 -12.325096 90)
			(size 0.519938 1.4986)
			(layers "F.Cu" "F.Mask" "F.Paste")
			(net "M_A_CPU1_SA_CB<7>")
		)
		(pad "206" smd rect
			(at 2.050034 -11.474958 90)
			(size 0.519938 1.4986)
			(layers "F.Cu" "F.Mask" "F.Paste")
			(net "GND")
		)
		(pad "207" smd rect
			(at 2.050034 -10.625074 90)
			(size 0.519938 1.4986)
			(layers "F.Cu" "F.Mask" "F.Paste")
			(net "M_A_CPU1_RESET_N")
		)
		(pad "208" smd rect
			(at 2.050034 -9.774936 90)
			(size 0.519938 1.4986)
			(layers "F.Cu" "F.Mask" "F.Paste")
			(net "GND")
		)
		(pad "209" smd rect
			(at 2.050034 -8.925052 90)
			(size 0.519938 1.4986)
			(layers "F.Cu" "F.Mask" "F.Paste")
			(net "M_A_CPU1_SA_CS_N<1>")
		)
		(pad "210" smd rect
			(at 2.050034 -8.074914 90)
			(size 0.519938 1.4986)
			(layers "F.Cu" "F.Mask" "F.Paste")
			(net "GND")
		)
		(pad "211" smd rect
			(at 2.050034 -7.22503 90)
			(size 0.519938 1.4986)
			(layers "F.Cu" "F.Mask" "F.Paste")
			(net "M_A_CPU1_SA_CA<1>")
		)
		(pad "212" smd rect
			(at 2.050034 -6.374892 90)
			(size 0.519938 1.4986)
			(layers "F.Cu" "F.Mask" "F.Paste")
			(net "GND")
		)
		(pad "213" smd rect
			(at 2.050034 -5.525008 90)
			(size 0.519938 1.4986)
			(layers "F.Cu" "F.Mask" "F.Paste")
			(net "M_A_CPU1_SA_CA<3>")
		)
		(pad "214" smd rect
			(at 2.050034 -4.675124 90)
			(size 0.519938 1.4986)
			(layers "F.Cu" "F.Mask" "F.Paste")
			(net "GND")
		)
		(pad "215" smd rect
			(at 2.050034 -3.824986 90)
			(size 0.519938 1.4986)
			(layers "F.Cu" "F.Mask" "F.Paste")
			(net "M_A_CPU1_SA_CA<5>")
		)
		(pad "216" smd rect
			(at 2.050034 -2.975102 90)
			(size 0.519938 1.4986)
			(layers "F.Cu" "F.Mask" "F.Paste")
			(net "GND")
		)
		(pad "217" smd rect
			(at 2.050034 -2.124964 90)
			(size 0.519938 1.4986)
			(layers "F.Cu" "F.Mask" "F.Paste")
			(net "M_A_CPU1_CLK_DP<0>")
		)
		(pad "218" smd rect
			(at 2.050034 -1.27508 90)
			(size 0.519938 1.4986)
			(layers "F.Cu" "F.Mask" "F.Paste")
			(net "M_A_CPU1_CLK_DN<0>")
		)
		(pad "219" smd rect
			(at 2.050034 -0.424942 90)
			(size 0.519938 1.4986)
			(layers "F.Cu" "F.Mask" "F.Paste")
			(net "GND")
		)
		(pad "220" smd rect
			(at 2.050034 5.525008 90)
			(size 0.519938 1.4986)
			(layers "F.Cu" "F.Mask" "F.Paste")
			(net "Net_2260")
		)
		(pad "221" smd rect
			(at 2.050034 6.374892 90)
			(size 0.519938 1.4986)
			(layers "F.Cu" "F.Mask" "F.Paste")
			(net "M_A_CPU1_SB_CA<1>")
		)
		(pad "222" smd rect
			(at 2.050034 7.22503 90)
			(size 0.519938 1.4986)
			(layers "F.Cu" "F.Mask" "F.Paste")
			(net "GND")
		)
		(pad "223" smd rect
			(at 2.050034 8.074914 90)
			(size 0.519938 1.4986)
			(layers "F.Cu" "F.Mask" "F.Paste")
			(net "M_A_CPU1_SB_CA<3>")
		)
		(pad "224" smd rect
			(at 2.050034 8.925052 90)
			(size 0.519938 1.4986)
			(layers "F.Cu" "F.Mask" "F.Paste")
			(net "GND")
		)
		(pad "225" smd rect
			(at 2.050034 9.774936 90)
			(size 0.519938 1.4986)
			(layers "F.Cu" "F.Mask" "F.Paste")
			(net "M_A_CPU1_SB_CA<5>")
		)
		(pad "226" smd rect
			(at 2.050034 10.625074 90)
			(size 0.519938 1.4986)
			(layers "F.Cu" "F.Mask" "F.Paste")
			(net "GND")
		)
	)
)
